(kicad_pcb
	(version 20260206)
	(generator "pcbnew")
	(generator_version "10.0")
	(general
		(thickness 1.6)
		(legacy_teardrops no)
	)
	(paper "A4")
	(title_block
		(title "04192023_DAF0TMB3IC0_F0TG_MB_C_brd_V02_OCP.brd")
		(comment 1 "Grand Teton / footprints 7951-7957 of 8354")
	)
	(layers
		(0 "F.Cu" signal "TOP")
		(4 "In1.Cu" signal "GND")
		(6 "In2.Cu" signal "IN1")
		(8 "In3.Cu" signal "GND1")
		(10 "In4.Cu" signal "IN2")
		(12 "In5.Cu" signal "GND2")
		(14 "In6.Cu" signal "IN3")
		(16 "In7.Cu" signal "GND3")
		(18 "In8.Cu" signal "VCC")
		(20 "In9.Cu" signal "VCC1")
		(22 "In10.Cu" signal "GND4")
		(24 "In11.Cu" signal "IN4")
		(26 "In12.Cu" signal "GND5")
		(28 "In13.Cu" signal "IN5")
		(30 "In14.Cu" signal "GND6")
		(32 "In15.Cu" signal "IN6")
		(34 "In16.Cu" signal "GND7")
		(2 "B.Cu" signal "BOTTOM")
		(9 "F.Adhes" user "F.Adhesive")
		(11 "B.Adhes" user "B.Adhesive")
		(13 "F.Paste" user "Package Geometry/Pastemask Top")
		(15 "B.Paste" user "Package Geometry/Pastemask Bottom")
		(5 "F.SilkS" user "Ref Des/Silkscreen Top")
		(7 "B.SilkS" user "Ref Des/Silkscreen Bottom")
		(1 "F.Mask" user "Board Geometry/Soldermask Top")
		(3 "B.Mask" user "Board Geometry/Soldermask Bottom")
		(17 "Dwgs.User" user "User.Drawings")
		(19 "Cmts.User" user "User.Comments")
		(21 "Eco1.User" user "User.Eco1")
		(23 "Eco2.User" user "User.Eco2")
		(25 "Edge.Cuts" user "Board Geometry/Outline")
		(27 "Margin" user)
		(31 "F.CrtYd" user "Package Geometry/Place Bound Top")
		(29 "B.CrtYd" user "Package Geometry/Place Bound Bottom")
		(35 "F.Fab" user "Ref Des/Assembly Top")
		(33 "B.Fab" user "Ref Des/Assembly Bottom")
	)
	(footprint ""
		(layer "B.Cu")
		(at 237.905544 -325.65721)
		(property "Reference" "R1234"
			(at 0 0 0)
			(layer "B.SilkS")
			(hide yes)
			(effects
				(font
					(size 1.27 1.27)
				)
				(justify mirror)
			)
		)
		(property "Value" ""
			(at 0 0 0)
			(layer "B.Fab")
			(effects
				(font
					(size 1.27 1.27)
				)
				(justify mirror)
			)
		)
		(duplicate_pad_numbers_are_jumpers no)
		(fp_line
			(start -0.7874 -0.4064)
			(end -0.7874 0.4064)
			(stroke
				(width 0.1524)
				(type default)
			)
			(layer "B.SilkS")
		)
		(fp_line
			(start -0.7874 0.4064)
			(end 0.7874 0.4064)
			(stroke
				(width 0.1524)
				(type default)
			)
			(layer "B.SilkS")
		)
		(fp_line
			(start 0.7874 -0.4064)
			(end -0.7874 -0.4064)
			(stroke
				(width 0.1524)
				(type default)
			)
			(layer "B.SilkS")
		)
		(fp_line
			(start 0.7874 0.4064)
			(end 0.7874 -0.4064)
			(stroke
				(width 0.1524)
				(type default)
			)
			(layer "B.SilkS")
		)
		(fp_line
			(start -0.67945 -0.3048)
			(end -0.67945 0.3048)
			(stroke
				(width 0.1)
				(type default)
			)
			(layer "B.Fab")
		)
		(fp_line
			(start -0.67945 0.3048)
			(end -0.120396 0.3048)
			(stroke
				(width 0.1)
				(type default)
			)
			(layer "B.Fab")
		)
		(fp_line
			(start -0.12065 -0.3048)
			(end -0.67945 -0.3048)
			(stroke
				(width 0.1)
				(type default)
			)
			(layer "B.Fab")
		)
		(fp_line
			(start -0.12065 -0.2794)
			(end -0.12065 -0.3048)
			(stroke
				(width 0.1)
				(type default)
			)
			(layer "B.Fab")
		)
		(fp_line
			(start -0.120396 0.2794)
			(end 0.12065 0.2794)
			(stroke
				(width 0.1)
				(type default)
			)
			(layer "B.Fab")
		)
		(fp_line
			(start -0.120396 0.3048)
			(end -0.120396 0.2794)
			(stroke
				(width 0.1)
				(type default)
			)
			(layer "B.Fab")
		)
		(fp_line
			(start 0.12065 -0.305054)
			(end 0.12065 -0.2794)
			(stroke
				(width 0.1)
				(type default)
			)
			(layer "B.Fab")
		)
		(fp_line
			(start 0.12065 -0.2794)
			(end -0.12065 -0.2794)
			(stroke
				(width 0.1)
				(type default)
			)
			(layer "B.Fab")
		)
		(fp_line
			(start 0.12065 0.2794)
			(end 0.12065 0.3048)
			(stroke
				(width 0.1)
				(type default)
			)
			(layer "B.Fab")
		)
		(fp_line
			(start 0.12065 0.3048)
			(end 0.67945 0.3048)
			(stroke
				(width 0.1)
				(type default)
			)
			(layer "B.Fab")
		)
		(fp_line
			(start 0.67945 -0.305054)
			(end 0.12065 -0.305054)
			(stroke
				(width 0.1)
				(type default)
			)
			(layer "B.Fab")
		)
		(fp_line
			(start 0.67945 0.3048)
			(end 0.67945 -0.305054)
			(stroke
				(width 0.1)
				(type default)
			)
			(layer "B.Fab")
		)
		(pad "1" smd circle
			(at 0.40005 0 180)
			(size 0 0)
			(layers "B.Cu" "B.Mask" "B.Paste")
			(net "P1V8_CPU1_RT_1D")
		)
		(pad "2" smd circle
			(at -0.40005 0 180)
			(size 0 0)
			(layers "B.Cu" "B.Mask" "B.Paste")
			(net "P1V8_CPU1_RT_1D_ADC")
		)
	)
	(footprint ""
		(layer "B.Cu")
		(at 41.525444 -349.386398 -90)
		(property "Reference" "PR281"
			(at 0 0 90)
			(layer "B.SilkS")
			(hide yes)
			(effects
				(font
					(size 1.27 1.27)
				)
				(justify mirror)
			)
		)
		(property "Value" ""
			(at 0 0 90)
			(layer "B.Fab")
			(effects
				(font
					(size 1.27 1.27)
				)
				(justify mirror)
			)
		)
		(duplicate_pad_numbers_are_jumpers no)
		(fp_line
			(start -0.7874 0.4064)
			(end 0.7874 0.4064)
			(stroke
				(width 0.1524)
				(type default)
			)
			(layer "B.SilkS")
		)
		(fp_line
			(start 0.7874 0.4064)
			(end 0.7874 -0.4064)
			(stroke
				(width 0.1524)
				(type default)
			)
			(layer "B.SilkS")
		)
		(fp_line
			(start -0.7874 -0.4064)
			(end -0.7874 0.4064)
			(stroke
				(width 0.1524)
				(type default)
			)
			(layer "B.SilkS")
		)
		(fp_line
			(start 0.7874 -0.4064)
			(end -0.7874 -0.4064)
			(stroke
				(width 0.1524)
				(type default)
			)
			(layer "B.SilkS")
		)
		(fp_line
			(start -0.67945 0.3048)
			(end -0.120396 0.3048)
			(stroke
				(width 0.1)
				(type default)
			)
			(layer "B.Fab")
		)
		(fp_line
			(start -0.120396 0.3048)
			(end -0.120396 0.2794)
			(stroke
				(width 0.1)
				(type default)
			)
			(layer "B.Fab")
		)
		(fp_line
			(start 0.12065 0.3048)
			(end 0.67945 0.3048)
			(stroke
				(width 0.1)
				(type default)
			)
			(layer "B.Fab")
		)
		(fp_line
			(start 0.67945 0.3048)
			(end 0.67945 -0.305054)
			(stroke
				(width 0.1)
				(type default)
			)
			(layer "B.Fab")
		)
		(fp_line
			(start -0.120396 0.2794)
			(end 0.12065 0.2794)
			(stroke
				(width 0.1)
				(type default)
			)
			(layer "B.Fab")
		)
		(fp_line
			(start 0.12065 0.2794)
			(end 0.12065 0.3048)
			(stroke
				(width 0.1)
				(type default)
			)
			(layer "B.Fab")
		)
		(fp_line
			(start -0.12065 -0.2794)
			(end -0.12065 -0.3048)
			(stroke
				(width 0.1)
				(type default)
			)
			(layer "B.Fab")
		)
		(fp_line
			(start 0.12065 -0.2794)
			(end -0.12065 -0.2794)
			(stroke
				(width 0.1)
				(type default)
			)
			(layer "B.Fab")
		)
		(fp_line
			(start -0.67945 -0.3048)
			(end -0.67945 0.3048)
			(stroke
				(width 0.1)
				(type default)
			)
			(layer "B.Fab")
		)
		(fp_line
			(start -0.12065 -0.3048)
			(end -0.67945 -0.3048)
			(stroke
				(width 0.1)
				(type default)
			)
			(layer "B.Fab")
		)
		(fp_line
			(start 0.12065 -0.305054)
			(end 0.12065 -0.2794)
			(stroke
				(width 0.1)
				(type default)
			)
			(layer "B.Fab")
		)
		(fp_line
			(start 0.67945 -0.305054)
			(end 0.12065 -0.305054)
			(stroke
				(width 0.1)
				(type default)
			)
			(layer "B.Fab")
		)
		(pad "1" smd circle
			(at 0.40005 0 90)
			(size 0 0)
			(layers "B.Cu" "B.Mask" "B.Paste")
			(net "PVDDIO_P1_VOS2")
		)
		(pad "2" smd circle
			(at -0.40005 0 90)
			(size 0 0)
			(layers "B.Cu" "B.Mask" "B.Paste")
			(net "PVDDIO_P1")
		)
	)
	(footprint ""
		(layer "B.Cu")
		(at 131.554474 -165.190932 90)
		(property "Reference" "PC339_2"
			(at 0 0 90)
			(layer "B.SilkS")
			(hide yes)
			(effects
				(font
					(size 1.27 1.27)
				)
				(justify mirror)
			)
		)
		(property "Value" ""
			(at 0 0 90)
			(layer "B.Fab")
			(effects
				(font
					(size 1.27 1.27)
				)
				(justify mirror)
			)
		)
		(duplicate_pad_numbers_are_jumpers no)
		(fp_line
			(start 1.524 -0.762)
			(end -1.524 -0.762)
			(stroke
				(width 0.1524)
				(type default)
			)
			(layer "B.SilkS")
		)
		(fp_line
			(start -1.524 -0.762)
			(end -1.524 0.762)
			(stroke
				(width 0.1524)
				(type default)
			)
			(layer "B.SilkS")
		)
		(fp_line
			(start 1.524 0.762)
			(end 1.524 -0.762)
			(stroke
				(width 0.1524)
				(type default)
			)
			(layer "B.SilkS")
		)
		(fp_line
			(start -1.524 0.762)
			(end 1.524 0.762)
			(stroke
				(width 0.1524)
				(type default)
			)
			(layer "B.SilkS")
		)
		(fp_line
			(start 1.1049 -0.724916)
			(end 1.1049 0.724916)
			(stroke
				(width 0.1)
				(type default)
			)
			(layer "B.Fab")
		)
		(fp_line
			(start -1.1049 -0.724916)
			(end 1.1049 -0.724916)
			(stroke
				(width 0.1)
				(type default)
			)
			(layer "B.Fab")
		)
		(fp_line
			(start 1.1049 0.724916)
			(end -1.1049 0.724916)
			(stroke
				(width 0.1)
				(type default)
			)
			(layer "B.Fab")
		)
		(fp_line
			(start -1.1049 0.724916)
			(end -1.1049 -0.724916)
			(stroke
				(width 0.1)
				(type default)
			)
			(layer "B.Fab")
		)
		(pad "1" smd rect
			(at 0.889 0 90)
			(size 1.016 1.27)
			(layers "B.Cu" "B.Mask" "B.Paste")
			(net "PVDDCR_SOC_P1")
		)
		(pad "2" smd rect
			(at -0.889 0 90)
			(size 1.016 1.27)
			(layers "B.Cu" "B.Mask" "B.Paste")
			(net "GND")
		)
	)
	(footprint ""
		(layer "B.Cu")
		(at 254.635 -340.76132 180)
		(property "Reference" "R1367"
			(at 0 0 0)
			(layer "B.SilkS")
			(hide yes)
			(effects
				(font
					(size 1.27 1.27)
				)
				(justify mirror)
			)
		)
		(property "Value" ""
			(at 0 0 0)
			(layer "B.Fab")
			(effects
				(font
					(size 1.27 1.27)
				)
				(justify mirror)
			)
		)
		(duplicate_pad_numbers_are_jumpers no)
		(fp_line
			(start 0.32512 0.175006)
			(end 0.32512 -0.175006)
			(stroke
				(width 0.1)
				(type default)
			)
			(layer "B.Fab")
		)
		(fp_line
			(start 0.32512 -0.175006)
			(end -0.32512 -0.175006)
			(stroke
				(width 0.1)
				(type default)
			)
			(layer "B.Fab")
		)
		(fp_line
			(start -0.32512 0.175006)
			(end 0.32512 0.175006)
			(stroke
				(width 0.1)
				(type default)
			)
			(layer "B.Fab")
		)
		(fp_line
			(start -0.32512 -0.175006)
			(end -0.32512 0.175006)
			(stroke
				(width 0.1)
				(type default)
			)
			(layer "B.Fab")
		)
		(pad "1" smd rect
			(at 0.2667 0)
			(size 0.3048 0.381)
			(layers "B.Cu" "B.Mask" "B.Paste")
			(net "P1V8_CPU0_RT_1D")
		)
		(pad "2" smd rect
			(at -0.2667 0 180)
			(size 0.3048 0.381)
			(layers "B.Cu" "B.Mask" "B.Paste")
			(net "SMB_RT_CPU0_P0_ROM_MUX_2D_R_SCL")
		)
	)
	(footprint ""
		(layer "B.Cu")
		(at 64.546988 -8.98398 90)
		(property "Reference" "C1835"
			(at 0 0 90)
			(layer "B.SilkS")
			(hide yes)
			(effects
				(font
					(size 1.27 1.27)
				)
				(justify mirror)
			)
		)
		(property "Value" ""
			(at 0 0 90)
			(layer "B.Fab")
			(effects
				(font
					(size 1.27 1.27)
				)
				(justify mirror)
			)
		)
		(duplicate_pad_numbers_are_jumpers no)
		(fp_line
			(start 0.7874 -0.4064)
			(end -0.7874 -0.4064)
			(stroke
				(width 0.1524)
				(type default)
			)
			(layer "B.SilkS")
		)
		(fp_line
			(start -0.7874 -0.4064)
			(end -0.7874 0.4064)
			(stroke
				(width 0.1524)
				(type default)
			)
			(layer "B.SilkS")
		)
		(fp_line
			(start 0.7874 0.4064)
			(end 0.7874 -0.4064)
			(stroke
				(width 0.1524)
				(type default)
			)
			(layer "B.SilkS")
		)
		(fp_line
			(start -0.7874 0.4064)
			(end 0.7874 0.4064)
			(stroke
				(width 0.1524)
				(type default)
			)
			(layer "B.SilkS")
		)
		(fp_line
			(start 0.67945 -0.305054)
			(end 0.12065 -0.305054)
			(stroke
				(width 0.1)
				(type default)
			)
			(layer "B.Fab")
		)
		(fp_line
			(start 0.12065 -0.305054)
			(end 0.12065 -0.2794)
			(stroke
				(width 0.1)
				(type default)
			)
			(layer "B.Fab")
		)
		(fp_line
			(start -0.12065 -0.3048)
			(end -0.67945 -0.3048)
			(stroke
				(width 0.1)
				(type default)
			)
			(layer "B.Fab")
		)
		(fp_line
			(start -0.67945 -0.3048)
			(end -0.67945 0.3048)
			(stroke
				(width 0.1)
				(type default)
			)
			(layer "B.Fab")
		)
		(fp_line
			(start 0.12065 -0.2794)
			(end -0.12065 -0.2794)
			(stroke
				(width 0.1)
				(type default)
			)
			(layer "B.Fab")
		)
		(fp_line
			(start -0.12065 -0.2794)
			(end -0.12065 -0.3048)
			(stroke
				(width 0.1)
				(type default)
			)
			(layer "B.Fab")
		)
		(fp_line
			(start 0.12065 0.2794)
			(end 0.12065 0.3048)
			(stroke
				(width 0.1)
				(type default)
			)
			(layer "B.Fab")
		)
		(fp_line
			(start -0.120396 0.2794)
			(end 0.12065 0.2794)
			(stroke
				(width 0.1)
				(type default)
			)
			(layer "B.Fab")
		)
		(fp_line
			(start 0.67945 0.3048)
			(end 0.67945 -0.305054)
			(stroke
				(width 0.1)
				(type default)
			)
			(layer "B.Fab")
		)
		(fp_line
			(start 0.12065 0.3048)
			(end 0.67945 0.3048)
			(stroke
				(width 0.1)
				(type default)
			)
			(layer "B.Fab")
		)
		(fp_line
			(start -0.120396 0.3048)
			(end -0.120396 0.2794)
			(stroke
				(width 0.1)
				(type default)
			)
			(layer "B.Fab")
		)
		(fp_line
			(start -0.67945 0.3048)
			(end -0.120396 0.3048)
			(stroke
				(width 0.1)
				(type default)
			)
			(layer "B.Fab")
		)
		(pad "1" smd circle
			(at 0.40005 0 270)
			(size 0 0)
			(layers "B.Cu" "B.Mask" "B.Paste")
			(net "P3V3_OCP_V3_2")
		)
		(pad "2" smd circle
			(at -0.40005 0 270)
			(size 0 0)
			(layers "B.Cu" "B.Mask" "B.Paste")
			(net "GND")
		)
	)
	(footprint ""
		(layer "B.Cu")
		(at 28.46324 -195.012564 180)
		(property "Reference" "R1584"
			(at 0 0 0)
			(layer "B.SilkS")
			(hide yes)
			(effects
				(font
					(size 1.27 1.27)
				)
				(justify mirror)
			)
		)
		(property "Value" ""
			(at 0 0 0)
			(layer "B.Fab")
			(effects
				(font
					(size 1.27 1.27)
				)
				(justify mirror)
			)
		)
		(duplicate_pad_numbers_are_jumpers no)
		(fp_line
			(start 0.7874 0.4064)
			(end 0.7874 -0.4064)
			(stroke
				(width 0.1524)
				(type default)
			)
			(layer "B.SilkS")
		)
		(fp_line
			(start 0.7874 -0.4064)
			(end -0.7874 -0.4064)
			(stroke
				(width 0.1524)
				(type default)
			)
			(layer "B.SilkS")
		)
		(fp_line
			(start -0.7874 0.4064)
			(end 0.7874 0.4064)
			(stroke
				(width 0.1524)
				(type default)
			)
			(layer "B.SilkS")
		)
		(fp_line
			(start -0.7874 -0.4064)
			(end -0.7874 0.4064)
			(stroke
				(width 0.1524)
				(type default)
			)
			(layer "B.SilkS")
		)
		(fp_line
			(start 0.67945 0.3048)
			(end 0.67945 -0.305054)
			(stroke
				(width 0.1)
				(type default)
			)
			(layer "B.Fab")
		)
		(fp_line
			(start 0.67945 -0.305054)
			(end 0.12065 -0.305054)
			(stroke
				(width 0.1)
				(type default)
			)
			(layer "B.Fab")
		)
		(fp_line
			(start 0.12065 0.3048)
			(end 0.67945 0.3048)
			(stroke
				(width 0.1)
				(type default)
			)
			(layer "B.Fab")
		)
		(fp_line
			(start 0.12065 0.2794)
			(end 0.12065 0.3048)
			(stroke
				(width 0.1)
				(type default)
			)
			(layer "B.Fab")
		)
		(fp_line
			(start 0.12065 -0.2794)
			(end -0.12065 -0.2794)
			(stroke
				(width 0.1)
				(type default)
			)
			(layer "B.Fab")
		)
		(fp_line
			(start 0.12065 -0.305054)
			(end 0.12065 -0.2794)
			(stroke
				(width 0.1)
				(type default)
			)
			(layer "B.Fab")
		)
		(fp_line
			(start -0.120396 0.3048)
			(end -0.120396 0.2794)
			(stroke
				(width 0.1)
				(type default)
			)
			(layer "B.Fab")
		)
		(fp_line
			(start -0.120396 0.2794)
			(end 0.12065 0.2794)
			(stroke
				(width 0.1)
				(type default)
			)
			(layer "B.Fab")
		)
		(fp_line
			(start -0.12065 -0.2794)
			(end -0.12065 -0.3048)
			(stroke
				(width 0.1)
				(type default)
			)
			(layer "B.Fab")
		)
		(fp_line
			(start -0.12065 -0.3048)
			(end -0.67945 -0.3048)
			(stroke
				(width 0.1)
				(type default)
			)
			(layer "B.Fab")
		)
		(fp_line
			(start -0.67945 0.3048)
			(end -0.120396 0.3048)
			(stroke
				(width 0.1)
				(type default)
			)
			(layer "B.Fab")
		)
		(fp_line
			(start -0.67945 -0.3048)
			(end -0.67945 0.3048)
			(stroke
				(width 0.1)
				(type default)
			)
			(layer "B.Fab")
		)
		(pad "1" smd circle
			(at 0.40005 0)
			(size 0 0)
			(layers "B.Cu" "B.Mask" "B.Paste")
			(net "I3C_SPD_DDRAF_CPU1_SCL")
		)
		(pad "2" smd circle
			(at -0.40005 0)
			(size 0 0)
			(layers "B.Cu" "B.Mask" "B.Paste")
			(net "I3C_SPD_DDRE_CPU1_SCL")
		)
	)
	(footprint ""
		(layer "B.Cu")
		(at 192.189608 -126.833376 -90)
		(property "Reference" "R158"
			(at 0 0 90)
			(layer "B.SilkS")
			(hide yes)
			(effects
				(font
					(size 1.27 1.27)
				)
				(justify mirror)
			)
		)
		(property "Value" ""
			(at 0 0 90)
			(layer "B.Fab")
			(effects
				(font
					(size 1.27 1.27)
				)
				(justify mirror)
			)
		)
		(duplicate_pad_numbers_are_jumpers no)
		(fp_line
			(start -0.7874 0.4064)
			(end 0.7874 0.4064)
			(stroke
				(width 0.1524)
				(type default)
			)
			(layer "B.SilkS")
		)
		(fp_line
			(start 0.7874 0.4064)
			(end 0.7874 -0.4064)
			(stroke
				(width 0.1524)
				(type default)
			)
			(layer "B.SilkS")
		)
		(fp_line
			(start -0.7874 -0.4064)
			(end -0.7874 0.4064)
			(stroke
				(width 0.1524)
				(type default)
			)
			(layer "B.SilkS")
		)
		(fp_line
			(start 0.7874 -0.4064)
			(end -0.7874 -0.4064)
			(stroke
				(width 0.1524)
				(type default)
			)
			(layer "B.SilkS")
		)
		(fp_line
			(start -0.67945 0.3048)
			(end -0.120396 0.3048)
			(stroke
				(width 0.1)
				(type default)
			)
			(layer "B.Fab")
		)
		(fp_line
			(start -0.120396 0.3048)
			(end -0.120396 0.2794)
			(stroke
				(width 0.1)
				(type default)
			)
			(layer "B.Fab")
		)
		(fp_line
			(start 0.12065 0.3048)
			(end 0.67945 0.3048)
			(stroke
				(width 0.1)
				(type default)
			)
			(layer "B.Fab")
		)
		(fp_line
			(start 0.67945 0.3048)
			(end 0.67945 -0.305054)
			(stroke
				(width 0.1)
				(type default)
			)
			(layer "B.Fab")
		)
		(fp_line
			(start -0.120396 0.2794)
			(end 0.12065 0.2794)
			(stroke
				(width 0.1)
				(type default)
			)
			(layer "B.Fab")
		)
		(fp_line
			(start 0.12065 0.2794)
			(end 0.12065 0.3048)
			(stroke
				(width 0.1)
				(type default)
			)
			(layer "B.Fab")
		)
		(fp_line
			(start -0.12065 -0.2794)
			(end -0.12065 -0.3048)
			(stroke
				(width 0.1)
				(type default)
			)
			(layer "B.Fab")
		)
		(fp_line
			(start 0.12065 -0.2794)
			(end -0.12065 -0.2794)
			(stroke
				(width 0.1)
				(type default)
			)
			(layer "B.Fab")
		)
		(fp_line
			(start -0.67945 -0.3048)
			(end -0.67945 0.3048)
			(stroke
				(width 0.1)
				(type default)
			)
			(layer "B.Fab")
		)
		(fp_line
			(start -0.12065 -0.3048)
			(end -0.67945 -0.3048)
			(stroke
				(width 0.1)
				(type default)
			)
			(layer "B.Fab")
		)
		(fp_line
			(start 0.12065 -0.305054)
			(end 0.12065 -0.2794)
			(stroke
				(width 0.1)
				(type default)
			)
			(layer "B.Fab")
		)
		(fp_line
			(start 0.67945 -0.305054)
			(end 0.12065 -0.305054)
			(stroke
				(width 0.1)
				(type default)
			)
			(layer "B.Fab")
		)
		(pad "1" smd circle
			(at 0.40005 0 90)
			(size 0 0)
			(layers "B.Cu" "B.Mask" "B.Paste")
			(net "FM_PLD_CPU0_PRSNT_HDT")
		)
		(pad "2" smd circle
			(at -0.40005 0 90)
			(size 0 0)
			(layers "B.Cu" "B.Mask" "B.Paste")
			(net "CPU0_HDT_BYPASS_SEL")
		)
	)
)
